# T6G (Grand Teton) — schematic netlist excerpt (pin names and nets, part order shuffled) for the footprints in the layout excerpt that follows; sources: Cadence DE-HDL packaged netlist, KiCad conversion of 04192023_DAF0TMB3IC0_F0TG_MB_C_brd_V02_OCP.brd

C6691  Q_CAP_DIFFBUS  DIFF BUS_0.22UF 6.3V 20% X6S  pkg C0201  page 330 : \1\ = P5E_CPU1_P1_TX_BUF_C_DP<15> ; \2\ = P5E_CPU1_P1_TX_BUF_DP<15>
R1288  Q_RES  4.7K 5% CHIP  pkg 0402LF  page 83 : A = FM_P0_PCC1_N ; B = PVDD18_S5_P0
C574  Q_CAP  10UF 6.3V 20% X6S  pkg C0402  page 279 : A = P0V9_CPU0_RT_2D ; B = GND

(kicad_pcb
	(version 20260206)
	(generator "pcbnew")
	(generator_version "10.0")
	(general
		(thickness 1.6)
		(legacy_teardrops no)
	)
	(paper "A4")
	(title_block
		(title "04192023_DAF0TMB3IC0_F0TG_MB_C_brd_V02_OCP.brd")
		(comment 1 "Grand Teton / footprints 6581-6583 of 8354")
	)
	(layers
		(0 "F.Cu" signal "TOP")
		(4 "In1.Cu" signal "GND")
		(6 "In2.Cu" signal "IN1")
		(8 "In3.Cu" signal "GND1")
		(10 "In4.Cu" signal "IN2")
		(12 "In5.Cu" signal "GND2")
		(14 "In6.Cu" signal "IN3")
		(16 "In7.Cu" signal "GND3")
		(18 "In8.Cu" signal "VCC")
		(20 "In9.Cu" signal "VCC1")
		(22 "In10.Cu" signal "GND4")
		(24 "In11.Cu" signal "IN4")
		(26 "In12.Cu" signal "GND5")
		(28 "In13.Cu" signal "IN5")
		(30 "In14.Cu" signal "GND6")
		(32 "In15.Cu" signal "IN6")
		(34 "In16.Cu" signal "GND7")
		(2 "B.Cu" signal "BOTTOM")
		(9 "F.Adhes" user "F.Adhesive")
		(11 "B.Adhes" user "B.Adhesive")
		(13 "F.Paste" user "Package Geometry/Pastemask Top")
		(15 "B.Paste" user "Package Geometry/Pastemask Bottom")
		(5 "F.SilkS" user "Ref Des/Silkscreen Top")
		(7 "B.SilkS" user "Ref Des/Silkscreen Bottom")
		(1 "F.Mask" user "Board Geometry/Soldermask Top")
		(3 "B.Mask" user "Board Geometry/Soldermask Bottom")
		(17 "Dwgs.User" user "User.Drawings")
		(19 "Cmts.User" user "User.Comments")
		(21 "Eco1.User" user "User.Eco1")
		(23 "Eco2.User" user "User.Eco2")
		(25 "Edge.Cuts" user "Board Geometry/Outline")
		(27 "Margin" user)
		(31 "F.CrtYd" user "Package Geometry/Place Bound Top")
		(29 "B.CrtYd" user "Package Geometry/Place Bound Bottom")
		(35 "F.Fab" user "Ref Des/Assembly Top")
		(33 "B.Fab" user "Ref Des/Assembly Bottom")
	)
	(footprint ""
		(layer "B.Cu")
		(at 310.590946 -398.942052 90)
		(property "Reference" "C574"
			(at 0 0 90)
			(layer "B.SilkS")
			(hide yes)
			(effects
				(font
					(size 1.27 1.27)
				)
				(justify mirror)
			)
		)
		(property "Value" ""
			(at 0 0 90)
			(layer "B.Fab")
			(effects
				(font
					(size 1.27 1.27)
				)
				(justify mirror)
			)
		)
		(duplicate_pad_numbers_are_jumpers no)
		(fp_line
			(start 0.7874 -0.4064)
			(end -0.7874 -0.4064)
			(stroke
				(width 0.1524)
				(type default)
			)
			(layer "B.SilkS")
		)
		(fp_line
			(start -0.7874 -0.4064)
			(end -0.7874 0.4064)
			(stroke
				(width 0.1524)
				(type default)
			)
			(layer "B.SilkS")
		)
		(fp_line
			(start 0.7874 0.4064)
			(end 0.7874 -0.4064)
			(stroke
				(width 0.1524)
				(type default)
			)
			(layer "B.SilkS")
		)
		(fp_line
			(start -0.7874 0.4064)
			(end 0.7874 0.4064)
			(stroke
				(width 0.1524)
				(type default)
			)
			(layer "B.SilkS")
		)
		(fp_line
			(start 0.67945 -0.305054)
			(end 0.12065 -0.305054)
			(stroke
				(width 0.1)
				(type default)
			)
			(layer "B.Fab")
		)
		(fp_line
			(start 0.12065 -0.305054)
			(end 0.12065 -0.2794)
			(stroke
				(width 0.1)
				(type default)
			)
			(layer "B.Fab")
		)
		(fp_line
			(start -0.12065 -0.3048)
			(end -0.67945 -0.3048)
			(stroke
				(width 0.1)
				(type default)
			)
			(layer "B.Fab")
		)
		(fp_line
			(start -0.67945 -0.3048)
			(end -0.67945 0.3048)
			(stroke
				(width 0.1)
				(type default)
			)
			(layer "B.Fab")
		)
		(fp_line
			(start 0.12065 -0.2794)
			(end -0.12065 -0.2794)
			(stroke
				(width 0.1)
				(type default)
			)
			(layer "B.Fab")
		)
		(fp_line
			(start -0.12065 -0.2794)
			(end -0.12065 -0.3048)
			(stroke
				(width 0.1)
				(type default)
			)
			(layer "B.Fab")
		)
		(fp_line
			(start 0.12065 0.2794)
			(end 0.12065 0.3048)
			(stroke
				(width 0.1)
				(type default)
			)
			(layer "B.Fab")
		)
		(fp_line
			(start -0.120396 0.2794)
			(end 0.12065 0.2794)
			(stroke
				(width 0.1)
				(type default)
			)
			(layer "B.Fab")
		)
		(fp_line
			(start 0.67945 0.3048)
			(end 0.67945 -0.305054)
			(stroke
				(width 0.1)
				(type default)
			)
			(layer "B.Fab")
		)
		(fp_line
			(start 0.12065 0.3048)
			(end 0.67945 0.3048)
			(stroke
				(width 0.1)
				(type default)
			)
			(layer "B.Fab")
		)
		(fp_line
			(start -0.120396 0.3048)
			(end -0.120396 0.2794)
			(stroke
				(width 0.1)
				(type default)
			)
			(layer "B.Fab")
		)
		(fp_line
			(start -0.67945 0.3048)
			(end -0.120396 0.3048)
			(stroke
				(width 0.1)
				(type default)
			)
			(layer "B.Fab")
		)
		(pad "1" smd circle
			(at 0.40005 0 270)
			(size 0 0)
			(layers "B.Cu" "B.Mask" "B.Paste")
			(net "P0V9_CPU0_RT_2D")
		)
		(pad "2" smd circle
			(at -0.40005 0 270)
			(size 0 0)
			(layers "B.Cu" "B.Mask" "B.Paste")
			(net "GND")
		)
	)
	(footprint ""
		(layer "B.Cu")
		(at 96.163384 -408.517344 90)
		(property "Reference" "C6691"
			(at 0 0 90)
			(layer "B.SilkS")
			(hide yes)
			(effects
				(font
					(size 1.27 1.27)
				)
				(justify mirror)
			)
		)
		(property "Value" ""
			(at 0 0 90)
			(layer "B.Fab")
			(effects
				(font
					(size 1.27 1.27)
				)
				(justify mirror)
			)
		)
		(duplicate_pad_numbers_are_jumpers no)
		(fp_line
			(start 0.299974 -0.150114)
			(end -0.299974 -0.150114)
			(stroke
				(width 0.1)
				(type default)
			)
			(layer "B.Fab")
		)
		(fp_line
			(start -0.299974 -0.150114)
			(end -0.299974 0.150114)
			(stroke
				(width 0.1)
				(type default)
			)
			(layer "B.Fab")
		)
		(fp_line
			(start 0.299974 0.150114)
			(end 0.299974 -0.150114)
			(stroke
				(width 0.1)
				(type default)
			)
			(layer "B.Fab")
		)
		(fp_line
			(start -0.299974 0.150114)
			(end 0.299974 0.150114)
			(stroke
				(width 0.1)
				(type default)
			)
			(layer "B.Fab")
		)
		(pad "1" smd rect
			(at 0.2667 0 270)
			(size 0.3048 0.381)
			(layers "B.Cu" "B.Mask" "B.Paste")
			(net "P5E_CPU1_P1_TX_BUF_C_DP<15>")
		)
		(pad "2" smd rect
			(at -0.2667 0 270)
			(size 0.3048 0.381)
			(layers "B.Cu" "B.Mask" "B.Paste")
			(net "P5E_CPU1_P1_TX_BUF_DP<15>")
		)
	)
	(footprint ""
		(layer "B.Cu")
		(at 183.364886 -133.795008 -90)
		(property "Reference" "R1288"
			(at 0 0 90)
			(layer "B.SilkS")
			(hide yes)
			(effects
				(font
					(size 1.27 1.27)
				)
				(justify mirror)
			)
		)
		(property "Value" ""
			(at 0 0 90)
			(layer "B.Fab")
			(effects
				(font
					(size 1.27 1.27)
				)
				(justify mirror)
			)
		)
		(duplicate_pad_numbers_are_jumpers no)
		(fp_line
			(start -0.7874 0.4064)
			(end 0.7874 0.4064)
			(stroke
				(width 0.1524)
				(type default)
			)
			(layer "B.SilkS")
		)
		(fp_line
			(start 0.7874 0.4064)
			(end 0.7874 -0.4064)
			(stroke
				(width 0.1524)
				(type default)
			)
			(layer "B.SilkS")
		)
		(fp_line
			(start -0.7874 -0.4064)
			(end -0.7874 0.4064)
			(stroke
				(width 0.1524)
				(type default)
			)
			(layer "B.SilkS")
		)
		(fp_line
			(start 0.7874 -0.4064)
			(end -0.7874 -0.4064)
			(stroke
				(width 0.1524)
				(type default)
			)
			(layer "B.SilkS")
		)
		(fp_line
			(start -0.67945 0.3048)
			(end -0.120396 0.3048)
			(stroke
				(width 0.1)
				(type default)
			)
			(layer "B.Fab")
		)
		(fp_line
			(start -0.120396 0.3048)
			(end -0.120396 0.2794)
			(stroke
				(width 0.1)
				(type default)
			)
			(layer "B.Fab")
		)
		(fp_line
			(start 0.12065 0.3048)
			(end 0.67945 0.3048)
			(stroke
				(width 0.1)
				(type default)
			)
			(layer "B.Fab")
		)
		(fp_line
			(start 0.67945 0.3048)
			(end 0.67945 -0.305054)
			(stroke
				(width 0.1)
				(type default)
			)
			(layer "B.Fab")
		)
		(fp_line
			(start -0.120396 0.2794)
			(end 0.12065 0.2794)
			(stroke
				(width 0.1)
				(type default)
			)
			(layer "B.Fab")
		)
		(fp_line
			(start 0.12065 0.2794)
			(end 0.12065 0.3048)
			(stroke
				(width 0.1)
				(type default)
			)
			(layer "B.Fab")
		)
		(fp_line
			(start -0.12065 -0.2794)
			(end -0.12065 -0.3048)
			(stroke
				(width 0.1)
				(type default)
			)
			(layer "B.Fab")
		)
		(fp_line
			(start 0.12065 -0.2794)
			(end -0.12065 -0.2794)
			(stroke
				(width 0.1)
				(type default)
			)
			(layer "B.Fab")
		)
		(fp_line
			(start -0.67945 -0.3048)
			(end -0.67945 0.3048)
			(stroke
				(width 0.1)
				(type default)
			)
			(layer "B.Fab")
		)
		(fp_line
			(start -0.12065 -0.3048)
			(end -0.67945 -0.3048)
			(stroke
				(width 0.1)
				(type default)
			)
			(layer "B.Fab")
		)
		(fp_line
			(start 0.12065 -0.305054)
			(end 0.12065 -0.2794)
			(stroke
				(width 0.1)
				(type default)
			)
			(layer "B.Fab")
		)
		(fp_line
			(start 0.67945 -0.305054)
			(end 0.12065 -0.305054)
			(stroke
				(width 0.1)
				(type default)
			)
			(layer "B.Fab")
		)
		(pad "1" smd circle
			(at 0.40005 0 90)
			(size 0 0)
			(layers "B.Cu" "B.Mask" "B.Paste")
			(net "FM_P0_PCC1_N")
		)
		(pad "2" smd circle
			(at -0.40005 0 90)
			(size 0 0)
			(layers "B.Cu" "B.Mask" "B.Paste")
			(net "PVDD18_S5_P0")
		)
	)
)
